# BASEBOARD_FAB2 (Tioga Pass) — schematic netlist excerpt (pin names and nets, part order shuffled) for the footprints in the layout excerpt that follows; sources: Cadence DE-HDL packaged netlist, KiCad conversion of Wiwynn_Tioga_Pass_MB.brd

T1P36  TPAD-SE-2P-GP  pkg DISCRET-GA1  page 256 : \1\ = L14_50OHM_6INCH ; GND1 = GND
R6D10  RES  240 1.0% EMPTY  pkg 0402  page 90 : A = PVCCIO_CPU0 ; B = PU_CPU0_SOCKET_ID_1
R3D31  RES  0.0 5% EMPTY  pkg 0402  page 156 : A = FM_CPU_BMC_INIT ; B = H_CPU1_BMCINIT

(kicad_pcb
	(version 20260206)
	(generator "pcbnew")
	(generator_version "10.0")
	(general
		(thickness 1.6)
		(legacy_teardrops no)
	)
	(paper "A4")
	(title_block
		(title "Wiwynn_Tioga_Pass_MB.brd")
		(comment 1 "Tioga Pass / footprints 259-261 of 4770")
	)
	(layers
		(0 "F.Cu" signal "TOP")
		(4 "In1.Cu" signal "L2GND")
		(6 "In2.Cu" signal "L3")
		(8 "In3.Cu" signal "L4GND")
		(10 "In4.Cu" signal "L5")
		(12 "In5.Cu" signal "L6GND")
		(14 "In6.Cu" signal "L7VCC")
		(16 "In7.Cu" signal "L8VCC")
		(18 "In8.Cu" signal "L9GND")
		(20 "In9.Cu" signal "L10")
		(22 "In10.Cu" signal "L11GND")
		(24 "In11.Cu" signal "L12")
		(26 "In12.Cu" signal "L13GND")
		(2 "B.Cu" signal "BOTTOM")
		(9 "F.Adhes" user "F.Adhesive")
		(11 "B.Adhes" user "B.Adhesive")
		(13 "F.Paste" user "Package Geometry/Pastemask Top")
		(15 "B.Paste" user "Package Geometry/Pastemask Bottom")
		(5 "F.SilkS" user "Ref Des/Silkscreen Top")
		(7 "B.SilkS" user "Ref Des/Silkscreen Bottom")
		(1 "F.Mask" user "Board Geometry/Soldermask Top")
		(3 "B.Mask" user "Board Geometry/Soldermask Bottom")
		(17 "Dwgs.User" user "User.Drawings")
		(19 "Cmts.User" user "User.Comments")
		(21 "Eco1.User" user "User.Eco1")
		(23 "Eco2.User" user "User.Eco2")
		(25 "Edge.Cuts" user "Board Geometry/Outline")
		(27 "Margin" user)
		(31 "F.CrtYd" user "Package Geometry/Place Bound Top")
		(29 "B.CrtYd" user "Package Geometry/Place Bound Bottom")
		(35 "F.Fab" user "Ref Des/Assembly Top")
		(33 "B.Fab" user "Ref Des/Assembly Bottom")
	)
	(footprint ""
		(layer "F.Cu")
		(at 34.417 13.2715 -90)
		(property "Reference" "T1P36"
			(at 0 0 270)
			(layer "F.SilkS")
			(hide yes)
			(effects
				(font
					(size 1.27 1.27)
				)
			)
		)
		(property "Value" "*"
			(at 0 -3.44805 270)
			(unlocked yes)
			(layer "F.Fab")
			(hide yes)
			(effects
				(font
					(size 0.889 0.889)
					(thickness 0.1524)
				)
			)
		)
		(property "Device Type" "TPAD-SE-2P-GP_DISCRET-GA1-TPADA"
			(at 0 -4.97205 270)
			(unlocked yes)
			(layer "F.Fab")
			(hide yes)
			(effects
				(font
					(size 0.889 0.889)
					(thickness 0.1524)
				)
			)
		)
		(duplicate_pad_numbers_are_jumpers no)
		(fp_line
			(start -1.016 2.286)
			(end -1.016 -2.286)
			(stroke
				(width 0.1524)
				(type default)
			)
			(layer "F.SilkS")
		)
		(fp_line
			(start 1.016 2.286)
			(end -1.016 2.286)
			(stroke
				(width 0.1524)
				(type default)
			)
			(layer "F.SilkS")
		)
		(fp_line
			(start -1.016 -2.286)
			(end 1.016 -2.286)
			(stroke
				(width 0.1524)
				(type default)
			)
			(layer "F.SilkS")
		)
		(fp_line
			(start 1.016 -2.286)
			(end 1.016 2.286)
			(stroke
				(width 0.1524)
				(type default)
			)
			(layer "F.SilkS")
		)
		(fp_rect
			(start -1.27 2.54)
			(end 1.27 -2.54)
			(stroke
				(width 0)
				(type default)
			)
			(fill no)
			(layer "F.CrtYd")
		)
		(fp_rect
			(start -1.27 2.54)
			(end 1.27 -2.54)
			(stroke
				(width 0)
				(type default)
			)
			(fill no)
			(layer "F.Fab")
		)
		(pad "1" thru_hole circle
			(at 0 -1.27 270)
			(size 1.524 1.524)
			(drill 0.9144)
			(layers "*.Cu" "*.Mask")
			(remove_unused_layers no)
			(net "L14_50OHM_6INCH")
			(clearance -0.0508)
			(thermal_gap 0.127)
			(padstack
				(mode front_inner_back)
				(layer "Inner"
					(shape circle)
					(size 1.1684 1.1684)
					(clearance 0.127)
				)
				(layer "B.Cu"
					(shape circle)
					(size 1.524 1.524)
					(clearance -0.0508)
				)
			)
		)
		(pad "GND1" thru_hole rect
			(at 0 1.27 270)
			(size 1.524 1.524)
			(drill 0.9144)
			(layers "*.Cu" "*.Mask")
			(remove_unused_layers no)
			(net "GND")
			(clearance -0.0508)
			(thermal_gap 0.127)
			(padstack
				(mode front_inner_back)
				(layer "Inner"
					(shape circle)
					(size 1.1684 1.1684)
					(clearance 0.127)
				)
				(layer "B.Cu"
					(shape rect)
					(size 1.524 1.524)
					(clearance -0.0508)
				)
			)
		)
	)
	(footprint ""
		(layer "F.Cu")
		(at 116.2812 -74.5998 90)
		(property "Reference" "R3D31"
			(at 0 0 90)
			(layer "F.SilkS")
			(hide yes)
			(effects
				(font
					(size 1.27 1.27)
				)
			)
		)
		(property "Value" ""
			(at 0 0 90)
			(layer "F.Fab")
			(effects
				(font
					(size 1.27 1.27)
				)
			)
		)
		(duplicate_pad_numbers_are_jumpers no)
		(fp_poly
			(pts
				(xy -0.2794 -0.1016) (xy 0.2794 -0.1016) (xy 0.2794 0.9906) (xy -0.2794 0.9906)
			)
			(stroke
				(width 0)
				(type default)
			)
			(fill no)
			(layer "F.CrtYd")
		)
		(fp_line
			(start 0.2794 -0.1016)
			(end -0.2794 -0.1016)
			(stroke
				(width 0.1)
				(type default)
			)
			(layer "F.Fab")
		)
		(fp_line
			(start -0.2794 -0.1016)
			(end -0.2794 0.9906)
			(stroke
				(width 0.1)
				(type default)
			)
			(layer "F.Fab")
		)
		(fp_line
			(start 0.2794 0.9906)
			(end 0.2794 -0.1016)
			(stroke
				(width 0.1)
				(type default)
			)
			(layer "F.Fab")
		)
		(fp_line
			(start -0.2794 0.9906)
			(end 0.2794 0.9906)
			(stroke
				(width 0.1)
				(type default)
			)
			(layer "F.Fab")
		)
		(pad "1" smd rect
			(at 0 0 90)
			(size 0.508 0.508)
			(layers "F.Cu" "F.Mask" "F.Paste")
			(net "FM_CPU_BMC_INIT")
		)
		(pad "2" smd rect
			(at 0 0.889 90)
			(size 0.508 0.508)
			(layers "F.Cu" "F.Mask" "F.Paste")
			(net "H_CPU1_BMCINIT")
		)
		(zone
			(layer "F.Cu")
			(hatch none 0.5)
			(connect_pads
				(clearance 0)
			)
			(min_thickness 0.25)
			(keepout
				(tracks allowed)
				(vias not_allowed)
				(pads allowed)
				(copperpour not_allowed)
				(footprints allowed)
			)
			(placement
				(enabled no)
				(sheetname "")
			)
			(fill
				(thermal_gap 0.5)
				(thermal_bridge_width 0.5)
				(island_removal_mode 0)
			)
			(polygon
				(pts
					(xy 116.5352 -74.3458) (xy 116.5352 -74.8538) (xy 116.9162 -74.8538) (xy 116.9162 -74.3458)
				)
			)
		)
		(zone
			(layer "F.Cu")
			(hatch none 0.5)
			(connect_pads
				(clearance 0)
			)
			(min_thickness 0.25)
			(keepout
				(tracks not_allowed)
				(vias allowed)
				(pads allowed)
				(copperpour not_allowed)
				(footprints allowed)
			)
			(placement
				(enabled no)
				(sheetname "")
			)
			(fill
				(thermal_gap 0.5)
				(thermal_bridge_width 0.5)
				(island_removal_mode 0)
			)
			(polygon
				(pts
					(xy 116.9162 -74.3458) (xy 116.9162 -74.8538) (xy 116.5352 -74.8538) (xy 116.5352 -74.3458)
				)
			)
		)
	)
	(footprint ""
		(layer "F.Cu")
		(at 281.178 -72.263 90)
		(property "Reference" "R6D10"
			(at 0 0 90)
			(layer "F.SilkS")
			(hide yes)
			(effects
				(font
					(size 1.27 1.27)
				)
			)
		)
		(property "Value" ""
			(at 0 0 90)
			(layer "F.Fab")
			(effects
				(font
					(size 1.27 1.27)
				)
			)
		)
		(duplicate_pad_numbers_are_jumpers no)
		(fp_rect
			(start -0.2794 -0.1016)
			(end 0.2794 0.9906)
			(stroke
				(width 0)
				(type default)
			)
			(fill no)
			(layer "F.CrtYd")
		)
		(fp_line
			(start 0.2794 -0.1016)
			(end -0.2794 -0.1016)
			(stroke
				(width 0.1)
				(type default)
			)
			(layer "F.Fab")
		)
		(fp_line
			(start -0.2794 -0.1016)
			(end -0.2794 0.9906)
			(stroke
				(width 0.1)
				(type default)
			)
			(layer "F.Fab")
		)
		(fp_line
			(start 0.2794 0.9906)
			(end 0.2794 -0.1016)
			(stroke
				(width 0.1)
				(type default)
			)
			(layer "F.Fab")
		)
		(fp_line
			(start -0.2794 0.9906)
			(end 0.2794 0.9906)
			(stroke
				(width 0.1)
				(type default)
			)
			(layer "F.Fab")
		)
		(pad "1" smd rect
			(at 0 0 90)
			(size 0.508 0.508)
			(layers "F.Cu" "F.Mask" "F.Paste")
			(net "PVCCIO_CPU0")
		)
		(pad "2" smd rect
			(at 0 0.889 90)
			(size 0.508 0.508)
			(layers "F.Cu" "F.Mask" "F.Paste")
			(net "PU_CPU0_SOCKET_ID_1")
		)
		(zone
			(layer "F.Cu")
			(hatch none 0.5)
			(connect_pads
				(clearance 0)
			)
			(min_thickness 0.25)
			(keepout
				(tracks not_allowed)
				(vias allowed)
				(pads allowed)
				(copperpour not_allowed)
				(footprints allowed)
			)
			(placement
				(enabled no)
				(sheetname "")
			)
			(fill
				(thermal_gap 0.5)
				(thermal_bridge_width 0.5)
				(island_removal_mode 0)
			)
			(polygon
				(pts
					(xy 281.432 -72.009) (xy 281.813 -72.009) (xy 281.813 -72.517) (xy 281.432 -72.517)
				)
			)
		)
		(zone
			(layer "F.Cu")
			(hatch none 0.5)
			(connect_pads
				(clearance 0)
			)
			(min_thickness 0.25)
			(keepout
				(tracks allowed)
				(vias not_allowed)
				(pads allowed)
				(copperpour not_allowed)
				(footprints allowed)
			)
			(placement
				(enabled no)
				(sheetname "")
			)
			(fill
				(thermal_gap 0.5)
				(thermal_bridge_width 0.5)
				(island_removal_mode 0)
			)
			(polygon
				(pts
					(xy 281.432 -72.009) (xy 281.813 -72.009) (xy 281.813 -72.517) (xy 281.432 -72.517)
				)
			)
		)
	)
)
